# T6G (Grand Teton) — schematic netlist excerpt (pin names and nets, part order shuffled) for the footprints in the layout excerpt that follows; sources: Cadence DE-HDL packaged netlist, KiCad conversion of 04192023_DAF0TMB3IC0_F0TG_MB_C_brd_V02_OCP.brd

R1293  Q_RES  0 5% CHIP  pkg 0402LF  page 159 : A = I3C_SPD_DDRAF_CPU1_SCL ; B = I3C_SPD_DDRAF_CPU1_LVC1_SCL
R1117  Q_RES  6.19K 1% CHIP  pkg 0402LF  page 262 : A = MB0_P12V_STBY_PWRGD ; B = AGND_HSC

(kicad_pcb
	(version 20260206)
	(generator "pcbnew")
	(generator_version "10.0")
	(general
		(thickness 1.6)
		(legacy_teardrops no)
	)
	(paper "A4")
	(title_block
		(title "04192023_DAF0TMB3IC0_F0TG_MB_C_brd_V02_OCP.brd")
		(comment 1 "Grand Teton / footprints 3139-3141 of 8354")
	)
	(layers
		(0 "F.Cu" signal "TOP")
		(4 "In1.Cu" signal "GND")
		(6 "In2.Cu" signal "IN1")
		(8 "In3.Cu" signal "GND1")
		(10 "In4.Cu" signal "IN2")
		(12 "In5.Cu" signal "GND2")
		(14 "In6.Cu" signal "IN3")
		(16 "In7.Cu" signal "GND3")
		(18 "In8.Cu" signal "VCC")
		(20 "In9.Cu" signal "VCC1")
		(22 "In10.Cu" signal "GND4")
		(24 "In11.Cu" signal "IN4")
		(26 "In12.Cu" signal "GND5")
		(28 "In13.Cu" signal "IN5")
		(30 "In14.Cu" signal "GND6")
		(32 "In15.Cu" signal "IN6")
		(34 "In16.Cu" signal "GND7")
		(2 "B.Cu" signal "BOTTOM")
		(9 "F.Adhes" user "F.Adhesive")
		(11 "B.Adhes" user "B.Adhesive")
		(13 "F.Paste" user "Package Geometry/Pastemask Top")
		(15 "B.Paste" user "Package Geometry/Pastemask Bottom")
		(5 "F.SilkS" user "Ref Des/Silkscreen Top")
		(7 "B.SilkS" user "Ref Des/Silkscreen Bottom")
		(1 "F.Mask" user "Board Geometry/Soldermask Top")
		(3 "B.Mask" user "Board Geometry/Soldermask Bottom")
		(17 "Dwgs.User" user "User.Drawings")
		(19 "Cmts.User" user "User.Comments")
		(21 "Eco1.User" user "User.Eco1")
		(23 "Eco2.User" user "User.Eco2")
		(25 "Edge.Cuts" user "Board Geometry/Outline")
		(27 "Margin" user)
		(31 "F.CrtYd" user "Package Geometry/Place Bound Top")
		(29 "B.CrtYd" user "Package Geometry/Place Bound Bottom")
		(35 "F.Fab" user "Ref Des/Assembly Top")
		(33 "B.Fab" user "Ref Des/Assembly Bottom")
	)
	(footprint ""
		(layer "F.Cu")
		(at 178.689 -407.543 180)
		(property "Reference" "R1117"
			(at 0 0 180)
			(layer "F.SilkS")
			(hide yes)
			(effects
				(font
					(size 1.27 1.27)
				)
			)
		)
		(property "Value" ""
			(at 0 0 180)
			(layer "F.Fab")
			(effects
				(font
					(size 1.27 1.27)
				)
			)
		)
		(duplicate_pad_numbers_are_jumpers no)
		(fp_line
			(start 0.7874 0.4064)
			(end -0.7874 0.4064)
			(stroke
				(width 0.1524)
				(type default)
			)
			(layer "F.SilkS")
		)
		(fp_line
			(start 0.7874 -0.4064)
			(end 0.7874 0.4064)
			(stroke
				(width 0.1524)
				(type default)
			)
			(layer "F.SilkS")
		)
		(fp_line
			(start -0.7874 0.4064)
			(end -0.7874 -0.4064)
			(stroke
				(width 0.1524)
				(type default)
			)
			(layer "F.SilkS")
		)
		(fp_line
			(start -0.7874 -0.4064)
			(end 0.7874 -0.4064)
			(stroke
				(width 0.1524)
				(type default)
			)
			(layer "F.SilkS")
		)
		(fp_line
			(start 0.67945 0.3048)
			(end 0.120396 0.3048)
			(stroke
				(width 0.1)
				(type default)
			)
			(layer "F.Fab")
		)
		(fp_line
			(start 0.67945 -0.3048)
			(end 0.67945 0.3048)
			(stroke
				(width 0.1)
				(type default)
			)
			(layer "F.Fab")
		)
		(fp_line
			(start 0.12065 -0.2794)
			(end 0.12065 -0.3048)
			(stroke
				(width 0.1)
				(type default)
			)
			(layer "F.Fab")
		)
		(fp_line
			(start 0.12065 -0.3048)
			(end 0.67945 -0.3048)
			(stroke
				(width 0.1)
				(type default)
			)
			(layer "F.Fab")
		)
		(fp_line
			(start 0.120396 0.3048)
			(end 0.120396 0.2794)
			(stroke
				(width 0.1)
				(type default)
			)
			(layer "F.Fab")
		)
		(fp_line
			(start 0.120396 0.2794)
			(end -0.12065 0.2794)
			(stroke
				(width 0.1)
				(type default)
			)
			(layer "F.Fab")
		)
		(fp_line
			(start -0.12065 0.3048)
			(end -0.67945 0.3048)
			(stroke
				(width 0.1)
				(type default)
			)
			(layer "F.Fab")
		)
		(fp_line
			(start -0.12065 0.2794)
			(end -0.12065 0.3048)
			(stroke
				(width 0.1)
				(type default)
			)
			(layer "F.Fab")
		)
		(fp_line
			(start -0.12065 -0.2794)
			(end 0.12065 -0.2794)
			(stroke
				(width 0.1)
				(type default)
			)
			(layer "F.Fab")
		)
		(fp_line
			(start -0.12065 -0.305054)
			(end -0.12065 -0.2794)
			(stroke
				(width 0.1)
				(type default)
			)
			(layer "F.Fab")
		)
		(fp_line
			(start -0.67945 0.3048)
			(end -0.67945 -0.305054)
			(stroke
				(width 0.1)
				(type default)
			)
			(layer "F.Fab")
		)
		(fp_line
			(start -0.67945 -0.305054)
			(end -0.12065 -0.305054)
			(stroke
				(width 0.1)
				(type default)
			)
			(layer "F.Fab")
		)
		(pad "1" smd circle
			(at -0.40005 0 180)
			(size 0 0)
			(layers "F.Cu" "F.Mask" "F.Paste")
			(net "MB0_P12V_STBY_PWRGD")
		)
		(pad "2" smd circle
			(at 0.40005 0 180)
			(size 0 0)
			(layers "F.Cu" "F.Mask" "F.Paste")
			(net "AGND_HSC")
		)
	)
	(footprint ""
		(layer "F.Cu")
		(at 34.665158 -170.50766)
		(property "Reference" "R1293"
			(at 0 0 0)
			(layer "F.SilkS")
			(hide yes)
			(effects
				(font
					(size 1.27 1.27)
				)
			)
		)
		(property "Value" ""
			(at 0 0 0)
			(layer "F.Fab")
			(effects
				(font
					(size 1.27 1.27)
				)
			)
		)
		(duplicate_pad_numbers_are_jumpers no)
		(fp_line
			(start -0.7874 -0.4064)
			(end 0.7874 -0.4064)
			(stroke
				(width 0.1524)
				(type default)
			)
			(layer "F.SilkS")
		)
		(fp_line
			(start -0.7874 0.4064)
			(end -0.7874 -0.4064)
			(stroke
				(width 0.1524)
				(type default)
			)
			(layer "F.SilkS")
		)
		(fp_line
			(start 0.7874 -0.4064)
			(end 0.7874 0.4064)
			(stroke
				(width 0.1524)
				(type default)
			)
			(layer "F.SilkS")
		)
		(fp_line
			(start 0.7874 0.4064)
			(end -0.7874 0.4064)
			(stroke
				(width 0.1524)
				(type default)
			)
			(layer "F.SilkS")
		)
		(fp_line
			(start -0.67945 -0.305054)
			(end -0.12065 -0.305054)
			(stroke
				(width 0.1)
				(type default)
			)
			(layer "F.Fab")
		)
		(fp_line
			(start -0.67945 0.3048)
			(end -0.67945 -0.305054)
			(stroke
				(width 0.1)
				(type default)
			)
			(layer "F.Fab")
		)
		(fp_line
			(start -0.12065 -0.305054)
			(end -0.12065 -0.2794)
			(stroke
				(width 0.1)
				(type default)
			)
			(layer "F.Fab")
		)
		(fp_line
			(start -0.12065 -0.2794)
			(end 0.12065 -0.2794)
			(stroke
				(width 0.1)
				(type default)
			)
			(layer "F.Fab")
		)
		(fp_line
			(start -0.12065 0.2794)
			(end -0.12065 0.3048)
			(stroke
				(width 0.1)
				(type default)
			)
			(layer "F.Fab")
		)
		(fp_line
			(start -0.12065 0.3048)
			(end -0.67945 0.3048)
			(stroke
				(width 0.1)
				(type default)
			)
			(layer "F.Fab")
		)
		(fp_line
			(start 0.120396 0.2794)
			(end -0.12065 0.2794)
			(stroke
				(width 0.1)
				(type default)
			)
			(layer "F.Fab")
		)
		(fp_line
			(start 0.120396 0.3048)
			(end 0.120396 0.2794)
			(stroke
				(width 0.1)
				(type default)
			)
			(layer "F.Fab")
		)
		(fp_line
			(start 0.12065 -0.3048)
			(end 0.67945 -0.3048)
			(stroke
				(width 0.1)
				(type default)
			)
			(layer "F.Fab")
		)
		(fp_line
			(start 0.12065 -0.2794)
			(end 0.12065 -0.3048)
			(stroke
				(width 0.1)
				(type default)
			)
			(layer "F.Fab")
		)
		(fp_line
			(start 0.67945 -0.3048)
			(end 0.67945 0.3048)
			(stroke
				(width 0.1)
				(type default)
			)
			(layer "F.Fab")
		)
		(fp_line
			(start 0.67945 0.3048)
			(end 0.120396 0.3048)
			(stroke
				(width 0.1)
				(type default)
			)
			(layer "F.Fab")
		)
		(pad "1" smd rect
			(at -0.40005 0 180)
			(size 0.4572 0.508)
			(layers "F.Cu" "F.Mask" "F.Paste")
			(net "I3C_SPD_DDRAF_CPU1_SCL")
		)
		(pad "2" smd rect
			(at 0.40005 0 180)
			(size 0.4572 0.508)
			(layers "F.Cu" "F.Mask" "F.Paste")
			(net "I3C_SPD_DDRAF_CPU1_LVC1_SCL")
		)
	)
	(footprint ""
		(layer "F.Cu")
		(at 31.429706 19.444716 -90)
		(property "Reference" "U26_SRM"
			(at 0 0 270)
			(layer "F.SilkS")
			(hide yes)
			(effects
				(font
					(size 1.27 1.27)
				)
			)
		)
		(property "Value" ""
			(at 0 0 270)
			(layer "F.Fab")
			(effects
				(font
					(size 1.27 1.27)
				)
			)
		)
		(duplicate_pad_numbers_are_jumpers no)
		(pad "1" smd circle
			(at 0 0 270)
			(size 0.762 0.762)
			(layers "F.Cu" "F.Mask" "F.Paste")
			(net "Net_10786")
		)
	)
)
